# S9S_MB_2U (Grand Teton) — schematic netlist excerpt (pin names and nets, part order shuffled) for the footprints in the layout excerpt that follows; sources: Cadence DE-HDL packaged netlist, KiCad conversion of 03242023_DA0F0TMBIJ0_F0T_Motherboard_J_brd_V01_OCP.brd

C2018  Q_CAP  0.1UF 25V 10% X7R  pkg 0402  page 172 : A = P3V3 ; B = GND
PC242_P0_8  Q_CAP  1UF 16V 10% X6S  pkg C0402  page 270 : A = PVCCIN_CPU0 ; B = GND

(kicad_pcb
	(version 20260206)
	(generator "pcbnew")
	(generator_version "10.0")
	(general
		(thickness 1.6)
		(legacy_teardrops no)
	)
	(paper "A4")
	(title_block
		(title "03242023_DA0F0TMBIJ0_F0T_Motherboard_J_brd_V01_OCP.brd")
		(comment 1 "Grand Teton / footprints 1722-1723 of 6105")
	)
	(layers
		(0 "F.Cu" signal "TOP")
		(4 "In1.Cu" signal "GND")
		(6 "In2.Cu" signal "IN1")
		(8 "In3.Cu" signal "GND1")
		(10 "In4.Cu" signal "IN2")
		(12 "In5.Cu" signal "GND2")
		(14 "In6.Cu" signal "IN3")
		(16 "In7.Cu" signal "GND3")
		(18 "In8.Cu" signal "VCC")
		(20 "In9.Cu" signal "VCC1")
		(22 "In10.Cu" signal "GND4")
		(24 "In11.Cu" signal "IN4")
		(26 "In12.Cu" signal "GND5")
		(28 "In13.Cu" signal "IN5")
		(30 "In14.Cu" signal "GND6")
		(32 "In15.Cu" signal "IN6")
		(34 "In16.Cu" signal "GND7")
		(2 "B.Cu" signal "BOTTOM")
		(9 "F.Adhes" user "F.Adhesive")
		(11 "B.Adhes" user "B.Adhesive")
		(13 "F.Paste" user "Package Geometry/Pastemask Top")
		(15 "B.Paste" user "Package Geometry/Pastemask Bottom")
		(5 "F.SilkS" user "Ref Des/Silkscreen Top")
		(7 "B.SilkS" user "Ref Des/Silkscreen Bottom")
		(1 "F.Mask" user "Board Geometry/Soldermask Top")
		(3 "B.Mask" user "Board Geometry/Soldermask Bottom")
		(17 "Dwgs.User" user "User.Drawings")
		(19 "Cmts.User" user "User.Comments")
		(21 "Eco1.User" user "User.Eco1")
		(23 "Eco2.User" user "User.Eco2")
		(25 "Edge.Cuts" user "Board Geometry/Outline")
		(27 "Margin" user)
		(31 "F.CrtYd" user "Package Geometry/Place Bound Top")
		(29 "B.CrtYd" user "Package Geometry/Place Bound Bottom")
		(35 "F.Fab" user "Ref Des/Assembly Top")
		(33 "B.Fab" user "Ref Des/Assembly Bottom")
	)
	(footprint ""
		(layer "F.Cu")
		(at 155.690824 -52.674012)
		(property "Reference" "C2018"
			(at 0 0 0)
			(layer "F.SilkS")
			(hide yes)
			(effects
				(font
					(size 1.27 1.27)
				)
			)
		)
		(property "Value" ""
			(at 0 0 0)
			(layer "F.Fab")
			(effects
				(font
					(size 1.27 1.27)
				)
			)
		)
		(duplicate_pad_numbers_are_jumpers no)
		(fp_line
			(start -0.7874 -0.4064)
			(end 0.7874 -0.4064)
			(stroke
				(width 0.1524)
				(type default)
			)
			(layer "F.SilkS")
		)
		(fp_line
			(start -0.7874 0.4064)
			(end -0.7874 -0.4064)
			(stroke
				(width 0.1524)
				(type default)
			)
			(layer "F.SilkS")
		)
		(fp_line
			(start 0.7874 -0.4064)
			(end 0.7874 0.4064)
			(stroke
				(width 0.1524)
				(type default)
			)
			(layer "F.SilkS")
		)
		(fp_line
			(start 0.7874 0.4064)
			(end -0.7874 0.4064)
			(stroke
				(width 0.1524)
				(type default)
			)
			(layer "F.SilkS")
		)
		(fp_line
			(start -0.67945 -0.305054)
			(end -0.12065 -0.305054)
			(stroke
				(width 0.1)
				(type default)
			)
			(layer "F.Fab")
		)
		(fp_line
			(start -0.67945 0.3048)
			(end -0.67945 -0.305054)
			(stroke
				(width 0.1)
				(type default)
			)
			(layer "F.Fab")
		)
		(fp_line
			(start -0.12065 -0.305054)
			(end -0.12065 -0.2794)
			(stroke
				(width 0.1)
				(type default)
			)
			(layer "F.Fab")
		)
		(fp_line
			(start -0.12065 -0.2794)
			(end 0.12065 -0.2794)
			(stroke
				(width 0.1)
				(type default)
			)
			(layer "F.Fab")
		)
		(fp_line
			(start -0.12065 0.2794)
			(end -0.12065 0.3048)
			(stroke
				(width 0.1)
				(type default)
			)
			(layer "F.Fab")
		)
		(fp_line
			(start -0.12065 0.3048)
			(end -0.67945 0.3048)
			(stroke
				(width 0.1)
				(type default)
			)
			(layer "F.Fab")
		)
		(fp_line
			(start 0.120396 0.2794)
			(end -0.12065 0.2794)
			(stroke
				(width 0.1)
				(type default)
			)
			(layer "F.Fab")
		)
		(fp_line
			(start 0.120396 0.3048)
			(end 0.120396 0.2794)
			(stroke
				(width 0.1)
				(type default)
			)
			(layer "F.Fab")
		)
		(fp_line
			(start 0.12065 -0.3048)
			(end 0.67945 -0.3048)
			(stroke
				(width 0.1)
				(type default)
			)
			(layer "F.Fab")
		)
		(fp_line
			(start 0.12065 -0.2794)
			(end 0.12065 -0.3048)
			(stroke
				(width 0.1)
				(type default)
			)
			(layer "F.Fab")
		)
		(fp_line
			(start 0.67945 -0.3048)
			(end 0.67945 0.3048)
			(stroke
				(width 0.1)
				(type default)
			)
			(layer "F.Fab")
		)
		(fp_line
			(start 0.67945 0.3048)
			(end 0.120396 0.3048)
			(stroke
				(width 0.1)
				(type default)
			)
			(layer "F.Fab")
		)
		(pad "1" smd circle
			(at -0.40005 0)
			(size 0 0)
			(layers "F.Cu" "F.Mask" "F.Paste")
			(net "P3V3")
		)
		(pad "2" smd circle
			(at 0.40005 0)
			(size 0 0)
			(layers "F.Cu" "F.Mask" "F.Paste")
			(net "GND")
		)
	)
	(footprint ""
		(layer "F.Cu")
		(at 390.587484 -331.449172 90)
		(property "Reference" "PC242_P0_8"
			(at 0 0 90)
			(layer "F.SilkS")
			(hide yes)
			(effects
				(font
					(size 1.27 1.27)
				)
			)
		)
		(property "Value" ""
			(at 0 0 90)
			(layer "F.Fab")
			(effects
				(font
					(size 1.27 1.27)
				)
			)
		)
		(duplicate_pad_numbers_are_jumpers no)
		(fp_line
			(start 0.7874 -0.4064)
			(end 0.7874 0.4064)
			(stroke
				(width 0.1524)
				(type default)
			)
			(layer "F.SilkS")
		)
		(fp_line
			(start -0.7874 -0.4064)
			(end 0.7874 -0.4064)
			(stroke
				(width 0.1524)
				(type default)
			)
			(layer "F.SilkS")
		)
		(fp_line
			(start 0.7874 0.4064)
			(end -0.7874 0.4064)
			(stroke
				(width 0.1524)
				(type default)
			)
			(layer "F.SilkS")
		)
		(fp_line
			(start -0.7874 0.4064)
			(end -0.7874 -0.4064)
			(stroke
				(width 0.1524)
				(type default)
			)
			(layer "F.SilkS")
		)
		(fp_line
			(start -0.12065 -0.305054)
			(end -0.12065 -0.2794)
			(stroke
				(width 0.1)
				(type default)
			)
			(layer "F.Fab")
		)
		(fp_line
			(start -0.67945 -0.305054)
			(end -0.12065 -0.305054)
			(stroke
				(width 0.1)
				(type default)
			)
			(layer "F.Fab")
		)
		(fp_line
			(start 0.67945 -0.3048)
			(end 0.67945 0.3048)
			(stroke
				(width 0.1)
				(type default)
			)
			(layer "F.Fab")
		)
		(fp_line
			(start 0.12065 -0.3048)
			(end 0.67945 -0.3048)
			(stroke
				(width 0.1)
				(type default)
			)
			(layer "F.Fab")
		)
		(fp_line
			(start 0.12065 -0.2794)
			(end 0.12065 -0.3048)
			(stroke
				(width 0.1)
				(type default)
			)
			(layer "F.Fab")
		)
		(fp_line
			(start -0.12065 -0.2794)
			(end 0.12065 -0.2794)
			(stroke
				(width 0.1)
				(type default)
			)
			(layer "F.Fab")
		)
		(fp_line
			(start 0.120396 0.2794)
			(end -0.12065 0.2794)
			(stroke
				(width 0.1)
				(type default)
			)
			(layer "F.Fab")
		)
		(fp_line
			(start -0.12065 0.2794)
			(end -0.12065 0.3048)
			(stroke
				(width 0.1)
				(type default)
			)
			(layer "F.Fab")
		)
		(fp_line
			(start 0.67945 0.3048)
			(end 0.120396 0.3048)
			(stroke
				(width 0.1)
				(type default)
			)
			(layer "F.Fab")
		)
		(fp_line
			(start 0.120396 0.3048)
			(end 0.120396 0.2794)
			(stroke
				(width 0.1)
				(type default)
			)
			(layer "F.Fab")
		)
		(fp_line
			(start -0.12065 0.3048)
			(end -0.67945 0.3048)
			(stroke
				(width 0.1)
				(type default)
			)
			(layer "F.Fab")
		)
		(fp_line
			(start -0.67945 0.3048)
			(end -0.67945 -0.305054)
			(stroke
				(width 0.1)
				(type default)
			)
			(layer "F.Fab")
		)
		(pad "1" smd circle
			(at -0.40005 0 90)
			(size 0 0)
			(layers "F.Cu" "F.Mask" "F.Paste")
			(net "PVCCIN_CPU0")
		)
		(pad "2" smd circle
			(at 0.40005 0 90)
			(size 0 0)
			(layers "F.Cu" "F.Mask" "F.Paste")
			(net "GND")
		)
	)
)
